# S9S_MB_2U (Grand Teton) — schematic netlist excerpt (pin names and nets, part order shuffled) for the footprints in the layout excerpt that follows; sources: Cadence DE-HDL packaged netlist, KiCad conversion of 03242023_DA0F0TMBIJ0_F0T_Motherboard_J_brd_V01_OCP.brd

U340  AP331AWG7  AP331AWG-7 EMPTY  pkg SOT25  page 307
  \in-\  = UV_P2V5_COMP
  GND  = GND
  \in+\  = P12V_AUX_UV_TRIGGER
  OUTPUT  = IRQ_UV_DETECT_R2_N
  VCC  = P12V_AUX

R2238  Q_RES  4.99K 1% EMPTY  pkg 0402LF  page 306 : A = A_HSC_INAP ; B = GND

(kicad_pcb
	(version 20260206)
	(generator "pcbnew")
	(generator_version "10.0")
	(general
		(thickness 1.6)
		(legacy_teardrops no)
	)
	(paper "A4")
	(title_block
		(title "03242023_DA0F0TMBIJ0_F0T_Motherboard_J_brd_V01_OCP.brd")
		(comment 1 "Grand Teton / footprints 1073-1074 of 6105")
	)
	(layers
		(0 "F.Cu" signal "TOP")
		(4 "In1.Cu" signal "GND")
		(6 "In2.Cu" signal "IN1")
		(8 "In3.Cu" signal "GND1")
		(10 "In4.Cu" signal "IN2")
		(12 "In5.Cu" signal "GND2")
		(14 "In6.Cu" signal "IN3")
		(16 "In7.Cu" signal "GND3")
		(18 "In8.Cu" signal "VCC")
		(20 "In9.Cu" signal "VCC1")
		(22 "In10.Cu" signal "GND4")
		(24 "In11.Cu" signal "IN4")
		(26 "In12.Cu" signal "GND5")
		(28 "In13.Cu" signal "IN5")
		(30 "In14.Cu" signal "GND6")
		(32 "In15.Cu" signal "IN6")
		(34 "In16.Cu" signal "GND7")
		(2 "B.Cu" signal "BOTTOM")
		(9 "F.Adhes" user "F.Adhesive")
		(11 "B.Adhes" user "B.Adhesive")
		(13 "F.Paste" user "Package Geometry/Pastemask Top")
		(15 "B.Paste" user "Package Geometry/Pastemask Bottom")
		(5 "F.SilkS" user "Ref Des/Silkscreen Top")
		(7 "B.SilkS" user "Ref Des/Silkscreen Bottom")
		(1 "F.Mask" user "Board Geometry/Soldermask Top")
		(3 "B.Mask" user "Board Geometry/Soldermask Bottom")
		(17 "Dwgs.User" user "User.Drawings")
		(19 "Cmts.User" user "User.Comments")
		(21 "Eco1.User" user "User.Eco1")
		(23 "Eco2.User" user "User.Eco2")
		(25 "Edge.Cuts" user "Board Geometry/Outline")
		(27 "Margin" user)
		(31 "F.CrtYd" user "Package Geometry/Place Bound Top")
		(29 "B.CrtYd" user "Package Geometry/Place Bound Bottom")
		(35 "F.Fab" user "Ref Des/Assembly Top")
		(33 "B.Fab" user "Ref Des/Assembly Bottom")
	)
	(footprint ""
		(layer "F.Cu")
		(at 220.100652 -106.384344)
		(property "Reference" "R2238"
			(at 0 0 0)
			(layer "F.SilkS")
			(hide yes)
			(effects
				(font
					(size 1.27 1.27)
				)
			)
		)
		(property "Value" ""
			(at 0 0 0)
			(layer "F.Fab")
			(effects
				(font
					(size 1.27 1.27)
				)
			)
		)
		(duplicate_pad_numbers_are_jumpers no)
		(fp_line
			(start -0.7874 -0.4064)
			(end 0.7874 -0.4064)
			(stroke
				(width 0.1524)
				(type default)
			)
			(layer "F.SilkS")
		)
		(fp_line
			(start -0.7874 0.4064)
			(end -0.7874 -0.4064)
			(stroke
				(width 0.1524)
				(type default)
			)
			(layer "F.SilkS")
		)
		(fp_line
			(start 0.7874 -0.4064)
			(end 0.7874 0.4064)
			(stroke
				(width 0.1524)
				(type default)
			)
			(layer "F.SilkS")
		)
		(fp_line
			(start 0.7874 0.4064)
			(end -0.7874 0.4064)
			(stroke
				(width 0.1524)
				(type default)
			)
			(layer "F.SilkS")
		)
		(fp_line
			(start -0.67945 -0.305054)
			(end -0.12065 -0.305054)
			(stroke
				(width 0.1)
				(type default)
			)
			(layer "F.Fab")
		)
		(fp_line
			(start -0.67945 0.3048)
			(end -0.67945 -0.305054)
			(stroke
				(width 0.1)
				(type default)
			)
			(layer "F.Fab")
		)
		(fp_line
			(start -0.12065 -0.305054)
			(end -0.12065 -0.2794)
			(stroke
				(width 0.1)
				(type default)
			)
			(layer "F.Fab")
		)
		(fp_line
			(start -0.12065 -0.2794)
			(end 0.12065 -0.2794)
			(stroke
				(width 0.1)
				(type default)
			)
			(layer "F.Fab")
		)
		(fp_line
			(start -0.12065 0.2794)
			(end -0.12065 0.3048)
			(stroke
				(width 0.1)
				(type default)
			)
			(layer "F.Fab")
		)
		(fp_line
			(start -0.12065 0.3048)
			(end -0.67945 0.3048)
			(stroke
				(width 0.1)
				(type default)
			)
			(layer "F.Fab")
		)
		(fp_line
			(start 0.120396 0.2794)
			(end -0.12065 0.2794)
			(stroke
				(width 0.1)
				(type default)
			)
			(layer "F.Fab")
		)
		(fp_line
			(start 0.120396 0.3048)
			(end 0.120396 0.2794)
			(stroke
				(width 0.1)
				(type default)
			)
			(layer "F.Fab")
		)
		(fp_line
			(start 0.12065 -0.3048)
			(end 0.67945 -0.3048)
			(stroke
				(width 0.1)
				(type default)
			)
			(layer "F.Fab")
		)
		(fp_line
			(start 0.12065 -0.2794)
			(end 0.12065 -0.3048)
			(stroke
				(width 0.1)
				(type default)
			)
			(layer "F.Fab")
		)
		(fp_line
			(start 0.67945 -0.3048)
			(end 0.67945 0.3048)
			(stroke
				(width 0.1)
				(type default)
			)
			(layer "F.Fab")
		)
		(fp_line
			(start 0.67945 0.3048)
			(end 0.120396 0.3048)
			(stroke
				(width 0.1)
				(type default)
			)
			(layer "F.Fab")
		)
		(pad "1" smd circle
			(at -0.40005 0)
			(size 0 0)
			(layers "F.Cu" "F.Mask" "F.Paste")
			(net "A_HSC_INAP")
		)
		(pad "2" smd circle
			(at 0.40005 0)
			(size 0 0)
			(layers "F.Cu" "F.Mask" "F.Paste")
			(net "GND")
		)
	)
	(footprint ""
		(layer "F.Cu")
		(at 213.1568 -110.617 90)
		(property "Reference" "U340"
			(at 4.54533 -0.5588 0)
			(unlocked yes)
			(layer "F.SilkS")
			(effects
				(font
					(size 0.7874 0.5842)
					(thickness 0.1524)
				)
			)
		)
		(property "Value" ""
			(at 0 0 90)
			(layer "F.Fab")
			(effects
				(font
					(size 1.27 1.27)
				)
			)
		)
		(duplicate_pad_numbers_are_jumpers no)
		(fp_line
			(start 2.032 -1.549908)
			(end 2.032 1.549908)
			(stroke
				(width 0.1524)
				(type default)
			)
			(layer "F.SilkS")
		)
		(fp_line
			(start 0.508 -1.549908)
			(end 2.032 -1.549908)
			(stroke
				(width 0.1524)
				(type default)
			)
			(layer "F.SilkS")
		)
		(fp_line
			(start -0.508 -1.549908)
			(end 0 -0.762)
			(stroke
				(width 0.1524)
				(type default)
			)
			(layer "F.SilkS")
		)
		(fp_line
			(start -2.032 -1.549908)
			(end -0.508 -1.549908)
			(stroke
				(width 0.1524)
				(type default)
			)
			(layer "F.SilkS")
		)
		(fp_line
			(start 0 -0.762)
			(end 0.508 -1.549908)
			(stroke
				(width 0.1524)
				(type default)
			)
			(layer "F.SilkS")
		)
		(fp_line
			(start 2.032 1.549908)
			(end -2.032 1.549908)
			(stroke
				(width 0.1524)
				(type default)
			)
			(layer "F.SilkS")
		)
		(fp_line
			(start -2.032 1.549908)
			(end -2.032 -1.549908)
			(stroke
				(width 0.1524)
				(type default)
			)
			(layer "F.SilkS")
		)
		(fp_poly
			(pts
				(xy -2.37363 -1.825244) (xy -1.764538 -1.622298) (xy -1.967738 -2.231136)
			)
			(stroke
				(width 0)
				(type default)
			)
			(fill yes)
			(layer "F.SilkS")
		)
		(fp_line
			(start 0.849884 -1.549908)
			(end 0.849884 1.549908)
			(stroke
				(width 0.1)
				(type default)
			)
			(layer "F.Fab")
		)
		(fp_line
			(start -0.849884 -1.549908)
			(end 0.849884 -1.549908)
			(stroke
				(width 0.1)
				(type default)
			)
			(layer "F.Fab")
		)
		(fp_line
			(start 0.849884 1.549908)
			(end -0.849884 1.549908)
			(stroke
				(width 0.1)
				(type default)
			)
			(layer "F.Fab")
		)
		(fp_line
			(start -0.849884 1.549908)
			(end -0.849884 -1.549908)
			(stroke
				(width 0.1)
				(type default)
			)
			(layer "F.Fab")
		)
		(fp_poly
			(pts
				(xy -3.2004 -1.45796) (xy -3.2004 -0.44196) (xy -2.1844 -0.94996)
			)
			(stroke
				(width 0)
				(type default)
			)
			(fill yes)
			(layer "F.Fab")
		)
		(pad "1" smd rect
			(at -1.35001 -0.94996)
			(size 0.6096 1.0668)
			(layers "F.Cu" "F.Mask" "F.Paste")
			(net "UV_P2V5_COMP")
		)
		(pad "2" smd rect
			(at -1.35001 0)
			(size 0.6096 1.0668)
			(layers "F.Cu" "F.Mask" "F.Paste")
			(net "GND")
		)
		(pad "3" smd rect
			(at -1.35001 0.94996)
			(size 0.6096 1.0668)
			(layers "F.Cu" "F.Mask" "F.Paste")
			(net "P12V_AUX_UV_TRIGGER")
		)
		(pad "4" smd rect
			(at 1.35001 0.94996)
			(size 0.6096 1.0668)
			(layers "F.Cu" "F.Mask" "F.Paste")
			(net "IRQ_UV_DETECT_R2_N")
		)
		(pad "5" smd rect
			(at 1.35001 -0.94996)
			(size 0.6096 1.0668)
			(layers "F.Cu" "F.Mask" "F.Paste")
			(net "P12V_AUX")
		)
	)
)
